# S9S_MB_2U (Grand Teton) — schematic netlist excerpt (pin names and nets, part order shuffled) for the footprints in the layout excerpt that follows; sources: Cadence DE-HDL packaged netlist, KiCad conversion of 03242023_DA0F0TMBIJ0_F0T_Motherboard_J_brd_V01_OCP.brd

C50  Q_CAP  2.2UF 6.3V 20% X6S  pkg C0402  page 98 : A = P3V3_AUX ; B = GND
PC437  Q_CAP  22UF 4V 20% X6S  pkg C0805  page 294 : A = PVCCFA_EHV_CPU1 ; B = GND
C492  Q_CAP  47UF 4V 20% X6S  pkg C0805  page 75 : A = PVCCFA_EHV_CPU0 ; B = GND

(kicad_pcb
	(version 20260206)
	(generator "pcbnew")
	(generator_version "10.0")
	(general
		(thickness 1.6)
		(legacy_teardrops no)
	)
	(paper "A4")
	(title_block
		(title "03242023_DA0F0TMBIJ0_F0T_Motherboard_J_brd_V01_OCP.brd")
		(comment 1 "Grand Teton / footprints 4203-4205 of 6105")
	)
	(layers
		(0 "F.Cu" signal "TOP")
		(4 "In1.Cu" signal "GND")
		(6 "In2.Cu" signal "IN1")
		(8 "In3.Cu" signal "GND1")
		(10 "In4.Cu" signal "IN2")
		(12 "In5.Cu" signal "GND2")
		(14 "In6.Cu" signal "IN3")
		(16 "In7.Cu" signal "GND3")
		(18 "In8.Cu" signal "VCC")
		(20 "In9.Cu" signal "VCC1")
		(22 "In10.Cu" signal "GND4")
		(24 "In11.Cu" signal "IN4")
		(26 "In12.Cu" signal "GND5")
		(28 "In13.Cu" signal "IN5")
		(30 "In14.Cu" signal "GND6")
		(32 "In15.Cu" signal "IN6")
		(34 "In16.Cu" signal "GND7")
		(2 "B.Cu" signal "BOTTOM")
		(9 "F.Adhes" user "F.Adhesive")
		(11 "B.Adhes" user "B.Adhesive")
		(13 "F.Paste" user "Package Geometry/Pastemask Top")
		(15 "B.Paste" user "Package Geometry/Pastemask Bottom")
		(5 "F.SilkS" user "Ref Des/Silkscreen Top")
		(7 "B.SilkS" user "Ref Des/Silkscreen Bottom")
		(1 "F.Mask" user "Board Geometry/Soldermask Top")
		(3 "B.Mask" user "Board Geometry/Soldermask Bottom")
		(17 "Dwgs.User" user "User.Drawings")
		(19 "Cmts.User" user "User.Comments")
		(21 "Eco1.User" user "User.Eco1")
		(23 "Eco2.User" user "User.Eco2")
		(25 "Edge.Cuts" user "Board Geometry/Outline")
		(27 "Margin" user)
		(31 "F.CrtYd" user "Package Geometry/Place Bound Top")
		(29 "B.CrtYd" user "Package Geometry/Place Bound Bottom")
		(35 "F.Fab" user "Ref Des/Assembly Top")
		(33 "B.Fab" user "Ref Des/Assembly Bottom")
	)
	(footprint ""
		(layer "B.Cu")
		(at 351.841308 -255.853946 90)
		(property "Reference" "C492"
			(at 0 0 90)
			(layer "B.SilkS")
			(hide yes)
			(effects
				(font
					(size 1.27 1.27)
				)
				(justify mirror)
			)
		)
		(property "Value" ""
			(at 0 0 90)
			(layer "B.Fab")
			(effects
				(font
					(size 1.27 1.27)
				)
				(justify mirror)
			)
		)
		(duplicate_pad_numbers_are_jumpers no)
		(fp_line
			(start 1.524 -0.762)
			(end -1.524 -0.762)
			(stroke
				(width 0.1524)
				(type default)
			)
			(layer "B.SilkS")
		)
		(fp_line
			(start -1.524 -0.762)
			(end -1.524 0.762)
			(stroke
				(width 0.1524)
				(type default)
			)
			(layer "B.SilkS")
		)
		(fp_line
			(start 1.524 0.762)
			(end 1.524 -0.762)
			(stroke
				(width 0.1524)
				(type default)
			)
			(layer "B.SilkS")
		)
		(fp_line
			(start -1.524 0.762)
			(end 1.524 0.762)
			(stroke
				(width 0.1524)
				(type default)
			)
			(layer "B.SilkS")
		)
		(fp_line
			(start 1.1049 -0.724916)
			(end 1.1049 0.724916)
			(stroke
				(width 0.1)
				(type default)
			)
			(layer "B.Fab")
		)
		(fp_line
			(start -1.1049 -0.724916)
			(end 1.1049 -0.724916)
			(stroke
				(width 0.1)
				(type default)
			)
			(layer "B.Fab")
		)
		(fp_line
			(start 1.1049 0.724916)
			(end -1.1049 0.724916)
			(stroke
				(width 0.1)
				(type default)
			)
			(layer "B.Fab")
		)
		(fp_line
			(start -1.1049 0.724916)
			(end -1.1049 -0.724916)
			(stroke
				(width 0.1)
				(type default)
			)
			(layer "B.Fab")
		)
		(pad "1" smd rect
			(at 0.889 0 90)
			(size 1.016 1.27)
			(layers "B.Cu" "B.Mask" "B.Paste")
			(net "PVCCFA_EHV_CPU0")
		)
		(pad "2" smd rect
			(at -0.889 0 90)
			(size 1.016 1.27)
			(layers "B.Cu" "B.Mask" "B.Paste")
			(net "GND")
		)
	)
	(footprint ""
		(layer "B.Cu")
		(at 53.415946 -319.268856 180)
		(property "Reference" "C50"
			(at 0 0 0)
			(layer "B.SilkS")
			(hide yes)
			(effects
				(font
					(size 1.27 1.27)
				)
				(justify mirror)
			)
		)
		(property "Value" ""
			(at 0 0 0)
			(layer "B.Fab")
			(effects
				(font
					(size 1.27 1.27)
				)
				(justify mirror)
			)
		)
		(duplicate_pad_numbers_are_jumpers no)
		(fp_line
			(start 0.7874 0.4064)
			(end 0.7874 -0.4064)
			(stroke
				(width 0.1524)
				(type default)
			)
			(layer "B.SilkS")
		)
		(fp_line
			(start 0.7874 -0.4064)
			(end -0.7874 -0.4064)
			(stroke
				(width 0.1524)
				(type default)
			)
			(layer "B.SilkS")
		)
		(fp_line
			(start -0.7874 0.4064)
			(end 0.7874 0.4064)
			(stroke
				(width 0.1524)
				(type default)
			)
			(layer "B.SilkS")
		)
		(fp_line
			(start -0.7874 -0.4064)
			(end -0.7874 0.4064)
			(stroke
				(width 0.1524)
				(type default)
			)
			(layer "B.SilkS")
		)
		(fp_line
			(start 0.67945 0.3048)
			(end 0.67945 -0.305054)
			(stroke
				(width 0.1)
				(type default)
			)
			(layer "B.Fab")
		)
		(fp_line
			(start 0.67945 -0.305054)
			(end 0.12065 -0.305054)
			(stroke
				(width 0.1)
				(type default)
			)
			(layer "B.Fab")
		)
		(fp_line
			(start 0.12065 0.3048)
			(end 0.67945 0.3048)
			(stroke
				(width 0.1)
				(type default)
			)
			(layer "B.Fab")
		)
		(fp_line
			(start 0.12065 0.2794)
			(end 0.12065 0.3048)
			(stroke
				(width 0.1)
				(type default)
			)
			(layer "B.Fab")
		)
		(fp_line
			(start 0.12065 -0.2794)
			(end -0.12065 -0.2794)
			(stroke
				(width 0.1)
				(type default)
			)
			(layer "B.Fab")
		)
		(fp_line
			(start 0.12065 -0.305054)
			(end 0.12065 -0.2794)
			(stroke
				(width 0.1)
				(type default)
			)
			(layer "B.Fab")
		)
		(fp_line
			(start -0.120396 0.3048)
			(end -0.120396 0.2794)
			(stroke
				(width 0.1)
				(type default)
			)
			(layer "B.Fab")
		)
		(fp_line
			(start -0.120396 0.2794)
			(end 0.12065 0.2794)
			(stroke
				(width 0.1)
				(type default)
			)
			(layer "B.Fab")
		)
		(fp_line
			(start -0.12065 -0.2794)
			(end -0.12065 -0.3048)
			(stroke
				(width 0.1)
				(type default)
			)
			(layer "B.Fab")
		)
		(fp_line
			(start -0.12065 -0.3048)
			(end -0.67945 -0.3048)
			(stroke
				(width 0.1)
				(type default)
			)
			(layer "B.Fab")
		)
		(fp_line
			(start -0.67945 0.3048)
			(end -0.120396 0.3048)
			(stroke
				(width 0.1)
				(type default)
			)
			(layer "B.Fab")
		)
		(fp_line
			(start -0.67945 -0.3048)
			(end -0.67945 0.3048)
			(stroke
				(width 0.1)
				(type default)
			)
			(layer "B.Fab")
		)
		(pad "1" smd circle
			(at 0.40005 0)
			(size 0 0)
			(layers "B.Cu" "B.Mask" "B.Paste")
			(net "P3V3_AUX")
		)
		(pad "2" smd circle
			(at -0.40005 0)
			(size 0 0)
			(layers "B.Cu" "B.Mask" "B.Paste")
			(net "GND")
		)
	)
	(footprint ""
		(layer "B.Cu")
		(at 61.980572 -170.657774)
		(property "Reference" "PC437"
			(at 0 0 0)
			(layer "B.SilkS")
			(hide yes)
			(effects
				(font
					(size 1.27 1.27)
				)
				(justify mirror)
			)
		)
		(property "Value" ""
			(at 0 0 0)
			(layer "B.Fab")
			(effects
				(font
					(size 1.27 1.27)
				)
				(justify mirror)
			)
		)
		(duplicate_pad_numbers_are_jumpers no)
		(fp_line
			(start -1.524 -0.762)
			(end -1.524 0.762)
			(stroke
				(width 0.1524)
				(type default)
			)
			(layer "B.SilkS")
		)
		(fp_line
			(start -1.524 0.762)
			(end 1.524 0.762)
			(stroke
				(width 0.1524)
				(type default)
			)
			(layer "B.SilkS")
		)
		(fp_line
			(start 1.524 -0.762)
			(end -1.524 -0.762)
			(stroke
				(width 0.1524)
				(type default)
			)
			(layer "B.SilkS")
		)
		(fp_line
			(start 1.524 0.762)
			(end 1.524 -0.762)
			(stroke
				(width 0.1524)
				(type default)
			)
			(layer "B.SilkS")
		)
		(fp_line
			(start -1.1049 -0.724916)
			(end 1.1049 -0.724916)
			(stroke
				(width 0.1)
				(type default)
			)
			(layer "B.Fab")
		)
		(fp_line
			(start -1.1049 0.724916)
			(end -1.1049 -0.724916)
			(stroke
				(width 0.1)
				(type default)
			)
			(layer "B.Fab")
		)
		(fp_line
			(start 1.1049 -0.724916)
			(end 1.1049 0.724916)
			(stroke
				(width 0.1)
				(type default)
			)
			(layer "B.Fab")
		)
		(fp_line
			(start 1.1049 0.724916)
			(end -1.1049 0.724916)
			(stroke
				(width 0.1)
				(type default)
			)
			(layer "B.Fab")
		)
		(pad "1" smd rect
			(at 0.889 0)
			(size 1.016 1.27)
			(layers "B.Cu" "B.Mask" "B.Paste")
			(net "PVCCFA_EHV_CPU1")
		)
		(pad "2" smd rect
			(at -0.889 0)
			(size 1.016 1.27)
			(layers "B.Cu" "B.Mask" "B.Paste")
			(net "GND")
		)
	)
)
